# T6G (Grand Teton) — schematic netlist excerpt (pin names and nets, part order shuffled) for the footprints in the layout excerpt that follows; sources: Cadence DE-HDL packaged netlist, KiCad conversion of 04192023_DAF0TMB3IC0_F0TG_MB_C_brd_V02_OCP.brd

C1802  Q_CAP  0.1UF 25V 10% X7R  pkg 0402  page 127 : A = FM_SMB_1_ALERT_GPU_ISO_N ; B = GND
PR3986  Q_RES  2K 0.1% CHIP  pkg 0402LF  page 264 : A = HSC_CS_3 ; B = AGND_HSC

(kicad_pcb
	(version 20260206)
	(generator "pcbnew")
	(generator_version "10.0")
	(general
		(thickness 1.6)
		(legacy_teardrops no)
	)
	(paper "A4")
	(title_block
		(title "04192023_DAF0TMB3IC0_F0TG_MB_C_brd_V02_OCP.brd")
		(comment 1 "Grand Teton / footprints 2019-2020 of 8354")
	)
	(layers
		(0 "F.Cu" signal "TOP")
		(4 "In1.Cu" signal "GND")
		(6 "In2.Cu" signal "IN1")
		(8 "In3.Cu" signal "GND1")
		(10 "In4.Cu" signal "IN2")
		(12 "In5.Cu" signal "GND2")
		(14 "In6.Cu" signal "IN3")
		(16 "In7.Cu" signal "GND3")
		(18 "In8.Cu" signal "VCC")
		(20 "In9.Cu" signal "VCC1")
		(22 "In10.Cu" signal "GND4")
		(24 "In11.Cu" signal "IN4")
		(26 "In12.Cu" signal "GND5")
		(28 "In13.Cu" signal "IN5")
		(30 "In14.Cu" signal "GND6")
		(32 "In15.Cu" signal "IN6")
		(34 "In16.Cu" signal "GND7")
		(2 "B.Cu" signal "BOTTOM")
		(9 "F.Adhes" user "F.Adhesive")
		(11 "B.Adhes" user "B.Adhesive")
		(13 "F.Paste" user "Package Geometry/Pastemask Top")
		(15 "B.Paste" user "Package Geometry/Pastemask Bottom")
		(5 "F.SilkS" user "Ref Des/Silkscreen Top")
		(7 "B.SilkS" user "Ref Des/Silkscreen Bottom")
		(1 "F.Mask" user "Board Geometry/Soldermask Top")
		(3 "B.Mask" user "Board Geometry/Soldermask Bottom")
		(17 "Dwgs.User" user "User.Drawings")
		(19 "Cmts.User" user "User.Comments")
		(21 "Eco1.User" user "User.Eco1")
		(23 "Eco2.User" user "User.Eco2")
		(25 "Edge.Cuts" user "Board Geometry/Outline")
		(27 "Margin" user)
		(31 "F.CrtYd" user "Package Geometry/Place Bound Top")
		(29 "B.CrtYd" user "Package Geometry/Place Bound Bottom")
		(35 "F.Fab" user "Ref Des/Assembly Top")
		(33 "B.Fab" user "Ref Des/Assembly Bottom")
	)
	(footprint ""
		(layer "F.Cu")
		(at 117.094 -417.957 90)
		(property "Reference" "C1802"
			(at 0 0 90)
			(layer "F.SilkS")
			(hide yes)
			(effects
				(font
					(size 1.27 1.27)
				)
			)
		)
		(property "Value" ""
			(at 0 0 90)
			(layer "F.Fab")
			(effects
				(font
					(size 1.27 1.27)
				)
			)
		)
		(duplicate_pad_numbers_are_jumpers no)
		(fp_line
			(start 0.7874 -0.4064)
			(end 0.7874 0.4064)
			(stroke
				(width 0.1524)
				(type default)
			)
			(layer "F.SilkS")
		)
		(fp_line
			(start -0.7874 -0.4064)
			(end 0.7874 -0.4064)
			(stroke
				(width 0.1524)
				(type default)
			)
			(layer "F.SilkS")
		)
		(fp_line
			(start 0.7874 0.4064)
			(end -0.7874 0.4064)
			(stroke
				(width 0.1524)
				(type default)
			)
			(layer "F.SilkS")
		)
		(fp_line
			(start -0.7874 0.4064)
			(end -0.7874 -0.4064)
			(stroke
				(width 0.1524)
				(type default)
			)
			(layer "F.SilkS")
		)
		(fp_line
			(start -0.12065 -0.305054)
			(end -0.12065 -0.2794)
			(stroke
				(width 0.1)
				(type default)
			)
			(layer "F.Fab")
		)
		(fp_line
			(start -0.67945 -0.305054)
			(end -0.12065 -0.305054)
			(stroke
				(width 0.1)
				(type default)
			)
			(layer "F.Fab")
		)
		(fp_line
			(start 0.67945 -0.3048)
			(end 0.67945 0.3048)
			(stroke
				(width 0.1)
				(type default)
			)
			(layer "F.Fab")
		)
		(fp_line
			(start 0.12065 -0.3048)
			(end 0.67945 -0.3048)
			(stroke
				(width 0.1)
				(type default)
			)
			(layer "F.Fab")
		)
		(fp_line
			(start 0.12065 -0.2794)
			(end 0.12065 -0.3048)
			(stroke
				(width 0.1)
				(type default)
			)
			(layer "F.Fab")
		)
		(fp_line
			(start -0.12065 -0.2794)
			(end 0.12065 -0.2794)
			(stroke
				(width 0.1)
				(type default)
			)
			(layer "F.Fab")
		)
		(fp_line
			(start 0.120396 0.2794)
			(end -0.12065 0.2794)
			(stroke
				(width 0.1)
				(type default)
			)
			(layer "F.Fab")
		)
		(fp_line
			(start -0.12065 0.2794)
			(end -0.12065 0.3048)
			(stroke
				(width 0.1)
				(type default)
			)
			(layer "F.Fab")
		)
		(fp_line
			(start 0.67945 0.3048)
			(end 0.120396 0.3048)
			(stroke
				(width 0.1)
				(type default)
			)
			(layer "F.Fab")
		)
		(fp_line
			(start 0.120396 0.3048)
			(end 0.120396 0.2794)
			(stroke
				(width 0.1)
				(type default)
			)
			(layer "F.Fab")
		)
		(fp_line
			(start -0.12065 0.3048)
			(end -0.67945 0.3048)
			(stroke
				(width 0.1)
				(type default)
			)
			(layer "F.Fab")
		)
		(fp_line
			(start -0.67945 0.3048)
			(end -0.67945 -0.305054)
			(stroke
				(width 0.1)
				(type default)
			)
			(layer "F.Fab")
		)
		(pad "1" smd circle
			(at -0.40005 0 90)
			(size 0 0)
			(layers "F.Cu" "F.Mask" "F.Paste")
			(net "FM_SMB_1_ALERT_GPU_ISO_N")
		)
		(pad "2" smd circle
			(at 0.40005 0 90)
			(size 0 0)
			(layers "F.Cu" "F.Mask" "F.Paste")
			(net "GND")
		)
	)
	(footprint ""
		(layer "F.Cu")
		(at 215.4301 -400.972782 180)
		(property "Reference" "PR3986"
			(at 0 0 180)
			(layer "F.SilkS")
			(hide yes)
			(effects
				(font
					(size 1.27 1.27)
				)
			)
		)
		(property "Value" ""
			(at 0 0 180)
			(layer "F.Fab")
			(effects
				(font
					(size 1.27 1.27)
				)
			)
		)
		(duplicate_pad_numbers_are_jumpers no)
		(fp_line
			(start 0.7874 0.4064)
			(end -0.7874 0.4064)
			(stroke
				(width 0.1524)
				(type default)
			)
			(layer "F.SilkS")
		)
		(fp_line
			(start 0.7874 -0.4064)
			(end 0.7874 0.4064)
			(stroke
				(width 0.1524)
				(type default)
			)
			(layer "F.SilkS")
		)
		(fp_line
			(start -0.7874 0.4064)
			(end -0.7874 -0.4064)
			(stroke
				(width 0.1524)
				(type default)
			)
			(layer "F.SilkS")
		)
		(fp_line
			(start -0.7874 -0.4064)
			(end 0.7874 -0.4064)
			(stroke
				(width 0.1524)
				(type default)
			)
			(layer "F.SilkS")
		)
		(fp_line
			(start 0.67945 0.3048)
			(end 0.120396 0.3048)
			(stroke
				(width 0.1)
				(type default)
			)
			(layer "F.Fab")
		)
		(fp_line
			(start 0.67945 -0.3048)
			(end 0.67945 0.3048)
			(stroke
				(width 0.1)
				(type default)
			)
			(layer "F.Fab")
		)
		(fp_line
			(start 0.12065 -0.2794)
			(end 0.12065 -0.3048)
			(stroke
				(width 0.1)
				(type default)
			)
			(layer "F.Fab")
		)
		(fp_line
			(start 0.12065 -0.3048)
			(end 0.67945 -0.3048)
			(stroke
				(width 0.1)
				(type default)
			)
			(layer "F.Fab")
		)
		(fp_line
			(start 0.120396 0.3048)
			(end 0.120396 0.2794)
			(stroke
				(width 0.1)
				(type default)
			)
			(layer "F.Fab")
		)
		(fp_line
			(start 0.120396 0.2794)
			(end -0.12065 0.2794)
			(stroke
				(width 0.1)
				(type default)
			)
			(layer "F.Fab")
		)
		(fp_line
			(start -0.12065 0.3048)
			(end -0.67945 0.3048)
			(stroke
				(width 0.1)
				(type default)
			)
			(layer "F.Fab")
		)
		(fp_line
			(start -0.12065 0.2794)
			(end -0.12065 0.3048)
			(stroke
				(width 0.1)
				(type default)
			)
			(layer "F.Fab")
		)
		(fp_line
			(start -0.12065 -0.2794)
			(end 0.12065 -0.2794)
			(stroke
				(width 0.1)
				(type default)
			)
			(layer "F.Fab")
		)
		(fp_line
			(start -0.12065 -0.305054)
			(end -0.12065 -0.2794)
			(stroke
				(width 0.1)
				(type default)
			)
			(layer "F.Fab")
		)
		(fp_line
			(start -0.67945 0.3048)
			(end -0.67945 -0.305054)
			(stroke
				(width 0.1)
				(type default)
			)
			(layer "F.Fab")
		)
		(fp_line
			(start -0.67945 -0.305054)
			(end -0.12065 -0.305054)
			(stroke
				(width 0.1)
				(type default)
			)
			(layer "F.Fab")
		)
		(pad "1" smd circle
			(at -0.40005 0 180)
			(size 0 0)
			(layers "F.Cu" "F.Mask" "F.Paste")
			(net "HSC_CS_3")
		)
		(pad "2" smd circle
			(at 0.40005 0 180)
			(size 0 0)
			(layers "F.Cu" "F.Mask" "F.Paste")
			(net "AGND_HSC")
		)
	)
)
